(kicad_pcb
	(version 20260206)
	(generator "pcbnew")
	(generator_version "10.0")
	(general
		(thickness 1.6)
		(legacy_teardrops no)
	)
	(paper "A4")
	(title_block
		(title "01162023_DA0F0TEBIF0_F0T_Expander_BD_F_brd_V02_OCP.brd")
		(comment 1 "Grand Teton / footprints 3800-3806 of 9728")
	)
	(layers
		(0 "F.Cu" signal "TOP")
		(4 "In1.Cu" signal "GND")
		(6 "In2.Cu" signal "VCC")
		(8 "In3.Cu" signal "VCC1")
		(10 "In4.Cu" signal "GND1")
		(12 "In5.Cu" signal "IN1")
		(14 "In6.Cu" signal "GND2")
		(16 "In7.Cu" signal "IN2")
		(18 "In8.Cu" signal "GND3")
		(20 "In9.Cu" signal "IN3")
		(22 "In10.Cu" signal "GND4")
		(24 "In11.Cu" signal "IN4")
		(26 "In12.Cu" signal "GND5")
		(28 "In13.Cu" signal "IN5")
		(30 "In14.Cu" signal "GND6")
		(32 "In15.Cu" signal "IN6")
		(34 "In16.Cu" signal "GND7")
		(2 "B.Cu" signal "BOTTOM")
		(9 "F.Adhes" user "F.Adhesive")
		(11 "B.Adhes" user "B.Adhesive")
		(13 "F.Paste" user "Package Geometry/Pastemask Top")
		(15 "B.Paste" user "Package Geometry/Pastemask Bottom")
		(5 "F.SilkS" user "Ref Des/Silkscreen Top")
		(7 "B.SilkS" user "Ref Des/Silkscreen Bottom")
		(1 "F.Mask" user "Board Geometry/Soldermask Top")
		(3 "B.Mask" user "Board Geometry/Soldermask Bottom")
		(17 "Dwgs.User" user "User.Drawings")
		(19 "Cmts.User" user "User.Comments")
		(21 "Eco1.User" user "User.Eco1")
		(23 "Eco2.User" user "User.Eco2")
		(25 "Edge.Cuts" user "Board Geometry/Outline")
		(27 "Margin" user)
		(31 "F.CrtYd" user "Package Geometry/Place Bound Top")
		(29 "B.CrtYd" user "Package Geometry/Place Bound Bottom")
		(35 "F.Fab" user "Ref Des/Assembly Top")
		(33 "B.Fab" user "Ref Des/Assembly Bottom")
	)
	(footprint ""
		(layer "F.Cu")
		(at 129.243074 -277.644352)
		(property "Reference" "PC96"
			(at 0 0 0)
			(layer "F.SilkS")
			(hide yes)
			(effects
				(font
					(size 1.27 1.27)
				)
			)
		)
		(property "Value" ""
			(at 0 0 0)
			(layer "F.Fab")
			(effects
				(font
					(size 1.27 1.27)
				)
			)
		)
		(duplicate_pad_numbers_are_jumpers no)
		(fp_line
			(start -1.524 -0.762)
			(end 1.524 -0.762)
			(stroke
				(width 0.1524)
				(type default)
			)
			(layer "F.SilkS")
		)
		(fp_line
			(start -1.524 0.762)
			(end -1.524 -0.762)
			(stroke
				(width 0.1524)
				(type default)
			)
			(layer "F.SilkS")
		)
		(fp_line
			(start 1.524 -0.762)
			(end 1.524 0.762)
			(stroke
				(width 0.1524)
				(type default)
			)
			(layer "F.SilkS")
		)
		(fp_line
			(start 1.524 0.762)
			(end -1.524 0.762)
			(stroke
				(width 0.1524)
				(type default)
			)
			(layer "F.SilkS")
		)
		(fp_line
			(start -1.1049 -0.724916)
			(end -1.1049 0.724916)
			(stroke
				(width 0.1)
				(type default)
			)
			(layer "F.Fab")
		)
		(fp_line
			(start -1.1049 0.724916)
			(end 1.1049 0.724916)
			(stroke
				(width 0.1)
				(type default)
			)
			(layer "F.Fab")
		)
		(fp_line
			(start 1.1049 -0.724916)
			(end -1.1049 -0.724916)
			(stroke
				(width 0.1)
				(type default)
			)
			(layer "F.Fab")
		)
		(fp_line
			(start 1.1049 0.724916)
			(end 1.1049 -0.724916)
			(stroke
				(width 0.1)
				(type default)
			)
			(layer "F.Fab")
		)
		(pad "1" smd rect
			(at -0.889 0 180)
			(size 1.016 1.27)
			(layers "F.Cu" "F.Mask" "F.Paste")
			(net "SW_P12V_P0V8_PEX1_FLT")
		)
		(pad "2" smd rect
			(at 0.889 0 180)
			(size 1.016 1.27)
			(layers "F.Cu" "F.Mask" "F.Paste")
			(net "GND")
		)
	)
	(footprint ""
		(layer "F.Cu")
		(at 46.273974 -72.766682 90)
		(property "Reference" "PR6903"
			(at 0 0 90)
			(layer "F.SilkS")
			(hide yes)
			(effects
				(font
					(size 1.27 1.27)
				)
			)
		)
		(property "Value" ""
			(at 0 0 90)
			(layer "F.Fab")
			(effects
				(font
					(size 1.27 1.27)
				)
			)
		)
		(duplicate_pad_numbers_are_jumpers no)
		(fp_line
			(start 0.7874 -0.4064)
			(end 0.7874 0.4064)
			(stroke
				(width 0.1524)
				(type default)
			)
			(layer "F.SilkS")
		)
		(fp_line
			(start -0.7874 -0.4064)
			(end 0.7874 -0.4064)
			(stroke
				(width 0.1524)
				(type default)
			)
			(layer "F.SilkS")
		)
		(fp_line
			(start 0.7874 0.4064)
			(end -0.7874 0.4064)
			(stroke
				(width 0.1524)
				(type default)
			)
			(layer "F.SilkS")
		)
		(fp_line
			(start -0.7874 0.4064)
			(end -0.7874 -0.4064)
			(stroke
				(width 0.1524)
				(type default)
			)
			(layer "F.SilkS")
		)
		(fp_line
			(start -0.12065 -0.305054)
			(end -0.12065 -0.2794)
			(stroke
				(width 0.1)
				(type default)
			)
			(layer "F.Fab")
		)
		(fp_line
			(start -0.67945 -0.305054)
			(end -0.12065 -0.305054)
			(stroke
				(width 0.1)
				(type default)
			)
			(layer "F.Fab")
		)
		(fp_line
			(start 0.67945 -0.3048)
			(end 0.67945 0.3048)
			(stroke
				(width 0.1)
				(type default)
			)
			(layer "F.Fab")
		)
		(fp_line
			(start 0.12065 -0.3048)
			(end 0.67945 -0.3048)
			(stroke
				(width 0.1)
				(type default)
			)
			(layer "F.Fab")
		)
		(fp_line
			(start 0.12065 -0.2794)
			(end 0.12065 -0.3048)
			(stroke
				(width 0.1)
				(type default)
			)
			(layer "F.Fab")
		)
		(fp_line
			(start -0.12065 -0.2794)
			(end 0.12065 -0.2794)
			(stroke
				(width 0.1)
				(type default)
			)
			(layer "F.Fab")
		)
		(fp_line
			(start 0.120396 0.2794)
			(end -0.12065 0.2794)
			(stroke
				(width 0.1)
				(type default)
			)
			(layer "F.Fab")
		)
		(fp_line
			(start -0.12065 0.2794)
			(end -0.12065 0.3048)
			(stroke
				(width 0.1)
				(type default)
			)
			(layer "F.Fab")
		)
		(fp_line
			(start 0.67945 0.3048)
			(end 0.120396 0.3048)
			(stroke
				(width 0.1)
				(type default)
			)
			(layer "F.Fab")
		)
		(fp_line
			(start 0.120396 0.3048)
			(end 0.120396 0.2794)
			(stroke
				(width 0.1)
				(type default)
			)
			(layer "F.Fab")
		)
		(fp_line
			(start -0.12065 0.3048)
			(end -0.67945 0.3048)
			(stroke
				(width 0.1)
				(type default)
			)
			(layer "F.Fab")
		)
		(fp_line
			(start -0.67945 0.3048)
			(end -0.67945 -0.305054)
			(stroke
				(width 0.1)
				(type default)
			)
			(layer "F.Fab")
		)
		(pad "1" smd circle
			(at -0.40005 0 90)
			(size 0 0)
			(layers "F.Cu" "F.Mask" "F.Paste")
			(net "P12V_SSD1_CO_MODE")
		)
		(pad "2" smd circle
			(at 0.40005 0 90)
			(size 0 0)
			(layers "F.Cu" "F.Mask" "F.Paste")
			(net "GND")
		)
	)
	(footprint ""
		(layer "F.Cu")
		(at 330.874878 -56.977534 180)
		(property "Reference" "PC436"
			(at 0 0 180)
			(layer "F.SilkS")
			(hide yes)
			(effects
				(font
					(size 1.27 1.27)
				)
			)
		)
		(property "Value" ""
			(at 0 0 180)
			(layer "F.Fab")
			(effects
				(font
					(size 1.27 1.27)
				)
			)
		)
		(duplicate_pad_numbers_are_jumpers no)
		(fp_line
			(start 0.7874 0.4064)
			(end -0.7874 0.4064)
			(stroke
				(width 0.1524)
				(type default)
			)
			(layer "F.SilkS")
		)
		(fp_line
			(start 0.7874 -0.4064)
			(end 0.7874 0.4064)
			(stroke
				(width 0.1524)
				(type default)
			)
			(layer "F.SilkS")
		)
		(fp_line
			(start -0.7874 0.4064)
			(end -0.7874 -0.4064)
			(stroke
				(width 0.1524)
				(type default)
			)
			(layer "F.SilkS")
		)
		(fp_line
			(start -0.7874 -0.4064)
			(end 0.7874 -0.4064)
			(stroke
				(width 0.1524)
				(type default)
			)
			(layer "F.SilkS")
		)
		(fp_line
			(start 0.67945 0.3048)
			(end 0.120396 0.3048)
			(stroke
				(width 0.1)
				(type default)
			)
			(layer "F.Fab")
		)
		(fp_line
			(start 0.67945 -0.3048)
			(end 0.67945 0.3048)
			(stroke
				(width 0.1)
				(type default)
			)
			(layer "F.Fab")
		)
		(fp_line
			(start 0.12065 -0.2794)
			(end 0.12065 -0.3048)
			(stroke
				(width 0.1)
				(type default)
			)
			(layer "F.Fab")
		)
		(fp_line
			(start 0.12065 -0.3048)
			(end 0.67945 -0.3048)
			(stroke
				(width 0.1)
				(type default)
			)
			(layer "F.Fab")
		)
		(fp_line
			(start 0.120396 0.3048)
			(end 0.120396 0.2794)
			(stroke
				(width 0.1)
				(type default)
			)
			(layer "F.Fab")
		)
		(fp_line
			(start 0.120396 0.2794)
			(end -0.12065 0.2794)
			(stroke
				(width 0.1)
				(type default)
			)
			(layer "F.Fab")
		)
		(fp_line
			(start -0.12065 0.3048)
			(end -0.67945 0.3048)
			(stroke
				(width 0.1)
				(type default)
			)
			(layer "F.Fab")
		)
		(fp_line
			(start -0.12065 0.2794)
			(end -0.12065 0.3048)
			(stroke
				(width 0.1)
				(type default)
			)
			(layer "F.Fab")
		)
		(fp_line
			(start -0.12065 -0.2794)
			(end 0.12065 -0.2794)
			(stroke
				(width 0.1)
				(type default)
			)
			(layer "F.Fab")
		)
		(fp_line
			(start -0.12065 -0.305054)
			(end -0.12065 -0.2794)
			(stroke
				(width 0.1)
				(type default)
			)
			(layer "F.Fab")
		)
		(fp_line
			(start -0.67945 0.3048)
			(end -0.67945 -0.305054)
			(stroke
				(width 0.1)
				(type default)
			)
			(layer "F.Fab")
		)
		(fp_line
			(start -0.67945 -0.305054)
			(end -0.12065 -0.305054)
			(stroke
				(width 0.1)
				(type default)
			)
			(layer "F.Fab")
		)
		(pad "1" smd circle
			(at -0.40005 0 180)
			(size 0 0)
			(layers "F.Cu" "F.Mask" "F.Paste")
			(net "P12V_AUX")
		)
		(pad "2" smd circle
			(at 0.40005 0 180)
			(size 0 0)
			(layers "F.Cu" "F.Mask" "F.Paste")
			(net "GND")
		)
	)
	(footprint ""
		(layer "F.Cu")
		(at 132.91439 -184.656984 -90)
		(property "Reference" "R1114"
			(at 0 0 270)
			(layer "F.SilkS")
			(hide yes)
			(effects
				(font
					(size 1.27 1.27)
				)
			)
		)
		(property "Value" ""
			(at 0 0 270)
			(layer "F.Fab")
			(effects
				(font
					(size 1.27 1.27)
				)
			)
		)
		(duplicate_pad_numbers_are_jumpers no)
		(fp_line
			(start -0.7874 -0.4064)
			(end 0.7874 -0.4064)
			(stroke
				(width 0.1524)
				(type default)
			)
			(layer "F.SilkS")
		)
		(fp_line
			(start -0.67945 0.3048)
			(end -0.67945 -0.305054)
			(stroke
				(width 0.1)
				(type default)
			)
			(layer "F.Fab")
		)
		(fp_line
			(start -0.12065 0.3048)
			(end -0.67945 0.3048)
			(stroke
				(width 0.1)
				(type default)
			)
			(layer "F.Fab")
		)
		(fp_line
			(start 0.120396 0.3048)
			(end 0.120396 0.2794)
			(stroke
				(width 0.1)
				(type default)
			)
			(layer "F.Fab")
		)
		(fp_line
			(start 0.67945 0.3048)
			(end 0.120396 0.3048)
			(stroke
				(width 0.1)
				(type default)
			)
			(layer "F.Fab")
		)
		(fp_line
			(start -0.12065 0.2794)
			(end -0.12065 0.3048)
			(stroke
				(width 0.1)
				(type default)
			)
			(layer "F.Fab")
		)
		(fp_line
			(start 0.120396 0.2794)
			(end -0.12065 0.2794)
			(stroke
				(width 0.1)
				(type default)
			)
			(layer "F.Fab")
		)
		(fp_line
			(start -0.12065 -0.2794)
			(end 0.12065 -0.2794)
			(stroke
				(width 0.1)
				(type default)
			)
			(layer "F.Fab")
		)
		(fp_line
			(start 0.12065 -0.2794)
			(end 0.12065 -0.3048)
			(stroke
				(width 0.1)
				(type default)
			)
			(layer "F.Fab")
		)
		(fp_line
			(start 0.12065 -0.3048)
			(end 0.67945 -0.3048)
			(stroke
				(width 0.1)
				(type default)
			)
			(layer "F.Fab")
		)
		(fp_line
			(start 0.67945 -0.3048)
			(end 0.67945 0.3048)
			(stroke
				(width 0.1)
				(type default)
			)
			(layer "F.Fab")
		)
		(fp_line
			(start -0.67945 -0.305054)
			(end -0.12065 -0.305054)
			(stroke
				(width 0.1)
				(type default)
			)
			(layer "F.Fab")
		)
		(fp_line
			(start -0.12065 -0.305054)
			(end -0.12065 -0.2794)
			(stroke
				(width 0.1)
				(type default)
			)
			(layer "F.Fab")
		)
		(pad "1" smd circle
			(at -0.40005 0 270)
			(size 0 0)
			(layers "F.Cu" "F.Mask" "F.Paste")
			(net "CLK_100M_DB2000QL_GPU_REF1_R_DP")
		)
		(pad "2" smd circle
			(at 0.40005 0 270)
			(size 0 0)
			(layers "F.Cu" "F.Mask" "F.Paste")
			(net "CLK_100M_DB2000QL_GPU_REF1_DP")
		)
	)
	(footprint ""
		(layer "F.Cu")
		(at 106.596942 -117.627654 180)
		(property "Reference" "PR6864"
			(at 0 0 180)
			(layer "F.SilkS")
			(hide yes)
			(effects
				(font
					(size 1.27 1.27)
				)
			)
		)
		(property "Value" ""
			(at 0 0 180)
			(layer "F.Fab")
			(effects
				(font
					(size 1.27 1.27)
				)
			)
		)
		(duplicate_pad_numbers_are_jumpers no)
		(fp_line
			(start 0.7874 0.4064)
			(end -0.7874 0.4064)
			(stroke
				(width 0.1524)
				(type default)
			)
			(layer "F.SilkS")
		)
		(fp_line
			(start 0.7874 -0.4064)
			(end 0.7874 0.4064)
			(stroke
				(width 0.1524)
				(type default)
			)
			(layer "F.SilkS")
		)
		(fp_line
			(start -0.7874 0.4064)
			(end -0.7874 -0.4064)
			(stroke
				(width 0.1524)
				(type default)
			)
			(layer "F.SilkS")
		)
		(fp_line
			(start -0.7874 -0.4064)
			(end 0.7874 -0.4064)
			(stroke
				(width 0.1524)
				(type default)
			)
			(layer "F.SilkS")
		)
		(fp_line
			(start 0.67945 0.3048)
			(end 0.120396 0.3048)
			(stroke
				(width 0.1)
				(type default)
			)
			(layer "F.Fab")
		)
		(fp_line
			(start 0.67945 -0.3048)
			(end 0.67945 0.3048)
			(stroke
				(width 0.1)
				(type default)
			)
			(layer "F.Fab")
		)
		(fp_line
			(start 0.12065 -0.2794)
			(end 0.12065 -0.3048)
			(stroke
				(width 0.1)
				(type default)
			)
			(layer "F.Fab")
		)
		(fp_line
			(start 0.12065 -0.3048)
			(end 0.67945 -0.3048)
			(stroke
				(width 0.1)
				(type default)
			)
			(layer "F.Fab")
		)
		(fp_line
			(start 0.120396 0.3048)
			(end 0.120396 0.2794)
			(stroke
				(width 0.1)
				(type default)
			)
			(layer "F.Fab")
		)
		(fp_line
			(start 0.120396 0.2794)
			(end -0.12065 0.2794)
			(stroke
				(width 0.1)
				(type default)
			)
			(layer "F.Fab")
		)
		(fp_line
			(start -0.12065 0.3048)
			(end -0.67945 0.3048)
			(stroke
				(width 0.1)
				(type default)
			)
			(layer "F.Fab")
		)
		(fp_line
			(start -0.12065 0.2794)
			(end -0.12065 0.3048)
			(stroke
				(width 0.1)
				(type default)
			)
			(layer "F.Fab")
		)
		(fp_line
			(start -0.12065 -0.2794)
			(end 0.12065 -0.2794)
			(stroke
				(width 0.1)
				(type default)
			)
			(layer "F.Fab")
		)
		(fp_line
			(start -0.12065 -0.305054)
			(end -0.12065 -0.2794)
			(stroke
				(width 0.1)
				(type default)
			)
			(layer "F.Fab")
		)
		(fp_line
			(start -0.67945 0.3048)
			(end -0.67945 -0.305054)
			(stroke
				(width 0.1)
				(type default)
			)
			(layer "F.Fab")
		)
		(fp_line
			(start -0.67945 -0.305054)
			(end -0.12065 -0.305054)
			(stroke
				(width 0.1)
				(type default)
			)
			(layer "F.Fab")
		)
		(pad "1" smd circle
			(at -0.40005 0 180)
			(size 0 0)
			(layers "F.Cu" "F.Mask" "F.Paste")
			(net "P12V_NIC1_CO_OV_FB")
		)
		(pad "2" smd circle
			(at 0.40005 0 180)
			(size 0 0)
			(layers "F.Cu" "F.Mask" "F.Paste")
			(net "P12V_NIC1_R")
		)
	)
	(footprint ""
		(layer "F.Cu")
		(at 387.082792 -140.85697)
		(property "Reference" "R340"
			(at 0 0 0)
			(layer "F.SilkS")
			(hide yes)
			(effects
				(font
					(size 1.27 1.27)
				)
			)
		)
		(property "Value" ""
			(at 0 0 0)
			(layer "F.Fab")
			(effects
				(font
					(size 1.27 1.27)
				)
			)
		)
		(duplicate_pad_numbers_are_jumpers no)
		(fp_line
			(start -0.7874 -0.4064)
			(end 0.7874 -0.4064)
			(stroke
				(width 0.1524)
				(type default)
			)
			(layer "F.SilkS")
		)
		(fp_line
			(start -0.7874 0.4064)
			(end -0.7874 -0.4064)
			(stroke
				(width 0.1524)
				(type default)
			)
			(layer "F.SilkS")
		)
		(fp_line
			(start 0.7874 -0.4064)
			(end 0.7874 0.4064)
			(stroke
				(width 0.1524)
				(type default)
			)
			(layer "F.SilkS")
		)
		(fp_line
			(start 0.7874 0.4064)
			(end -0.7874 0.4064)
			(stroke
				(width 0.1524)
				(type default)
			)
			(layer "F.SilkS")
		)
		(fp_line
			(start -0.67945 -0.305054)
			(end -0.12065 -0.305054)
			(stroke
				(width 0.1)
				(type default)
			)
			(layer "F.Fab")
		)
		(fp_line
			(start -0.67945 0.3048)
			(end -0.67945 -0.305054)
			(stroke
				(width 0.1)
				(type default)
			)
			(layer "F.Fab")
		)
		(fp_line
			(start -0.12065 -0.305054)
			(end -0.12065 -0.2794)
			(stroke
				(width 0.1)
				(type default)
			)
			(layer "F.Fab")
		)
		(fp_line
			(start -0.12065 -0.2794)
			(end 0.12065 -0.2794)
			(stroke
				(width 0.1)
				(type default)
			)
			(layer "F.Fab")
		)
		(fp_line
			(start -0.12065 0.2794)
			(end -0.12065 0.3048)
			(stroke
				(width 0.1)
				(type default)
			)
			(layer "F.Fab")
		)
		(fp_line
			(start -0.12065 0.3048)
			(end -0.67945 0.3048)
			(stroke
				(width 0.1)
				(type default)
			)
			(layer "F.Fab")
		)
		(fp_line
			(start 0.120396 0.2794)
			(end -0.12065 0.2794)
			(stroke
				(width 0.1)
				(type default)
			)
			(layer "F.Fab")
		)
		(fp_line
			(start 0.120396 0.3048)
			(end 0.120396 0.2794)
			(stroke
				(width 0.1)
				(type default)
			)
			(layer "F.Fab")
		)
		(fp_line
			(start 0.12065 -0.3048)
			(end 0.67945 -0.3048)
			(stroke
				(width 0.1)
				(type default)
			)
			(layer "F.Fab")
		)
		(fp_line
			(start 0.12065 -0.2794)
			(end 0.12065 -0.3048)
			(stroke
				(width 0.1)
				(type default)
			)
			(layer "F.Fab")
		)
		(fp_line
			(start 0.67945 -0.3048)
			(end 0.67945 0.3048)
			(stroke
				(width 0.1)
				(type default)
			)
			(layer "F.Fab")
		)
		(fp_line
			(start 0.67945 0.3048)
			(end 0.120396 0.3048)
			(stroke
				(width 0.1)
				(type default)
			)
			(layer "F.Fab")
		)
		(pad "1" smd circle
			(at -0.40005 0)
			(size 0 0)
			(layers "F.Cu" "F.Mask" "F.Paste")
			(net "NIC6_BIF2_N")
		)
		(pad "2" smd circle
			(at 0.40005 0)
			(size 0 0)
			(layers "F.Cu" "F.Mask" "F.Paste")
			(net "GND")
		)
	)
	(footprint ""
		(layer "F.Cu")
		(at 296.54119 -213.523068 -90)
		(property "Reference" "R3400"
			(at 0 0 270)
			(layer "F.SilkS")
			(hide yes)
			(effects
				(font
					(size 1.27 1.27)
				)
			)
		)
		(property "Value" ""
			(at 0 0 270)
			(layer "F.Fab")
			(effects
				(font
					(size 1.27 1.27)
				)
			)
		)
		(duplicate_pad_numbers_are_jumpers no)
		(fp_line
			(start -0.7874 0.4064)
			(end -0.7874 -0.4064)
			(stroke
				(width 0.1524)
				(type default)
			)
			(layer "F.SilkS")
		)
		(fp_line
			(start 0.7874 0.4064)
			(end -0.7874 0.4064)
			(stroke
				(width 0.1524)
				(type default)
			)
			(layer "F.SilkS")
		)
		(fp_line
			(start -0.7874 -0.4064)
			(end 0.7874 -0.4064)
			(stroke
				(width 0.1524)
				(type default)
			)
			(layer "F.SilkS")
		)
		(fp_line
			(start 0.7874 -0.4064)
			(end 0.7874 0.4064)
			(stroke
				(width 0.1524)
				(type default)
			)
			(layer "F.SilkS")
		)
		(fp_line
			(start -0.67945 0.3048)
			(end -0.67945 -0.305054)
			(stroke
				(width 0.1)
				(type default)
			)
			(layer "F.Fab")
		)
		(fp_line
			(start -0.12065 0.3048)
			(end -0.67945 0.3048)
			(stroke
				(width 0.1)
				(type default)
			)
			(layer "F.Fab")
		)
		(fp_line
			(start 0.120396 0.3048)
			(end 0.120396 0.2794)
			(stroke
				(width 0.1)
				(type default)
			)
			(layer "F.Fab")
		)
		(fp_line
			(start 0.67945 0.3048)
			(end 0.120396 0.3048)
			(stroke
				(width 0.1)
				(type default)
			)
			(layer "F.Fab")
		)
		(fp_line
			(start -0.12065 0.2794)
			(end -0.12065 0.3048)
			(stroke
				(width 0.1)
				(type default)
			)
			(layer "F.Fab")
		)
		(fp_line
			(start 0.120396 0.2794)
			(end -0.12065 0.2794)
			(stroke
				(width 0.1)
				(type default)
			)
			(layer "F.Fab")
		)
		(fp_line
			(start -0.12065 -0.2794)
			(end 0.12065 -0.2794)
			(stroke
				(width 0.1)
				(type default)
			)
			(layer "F.Fab")
		)
		(fp_line
			(start 0.12065 -0.2794)
			(end 0.12065 -0.3048)
			(stroke
				(width 0.1)
				(type default)
			)
			(layer "F.Fab")
		)
		(fp_line
			(start 0.12065 -0.3048)
			(end 0.67945 -0.3048)
			(stroke
				(width 0.1)
				(type default)
			)
			(layer "F.Fab")
		)
		(fp_line
			(start 0.67945 -0.3048)
			(end 0.67945 0.3048)
			(stroke
				(width 0.1)
				(type default)
			)
			(layer "F.Fab")
		)
		(fp_line
			(start -0.67945 -0.305054)
			(end -0.12065 -0.305054)
			(stroke
				(width 0.1)
				(type default)
			)
			(layer "F.Fab")
		)
		(fp_line
			(start -0.12065 -0.305054)
			(end -0.12065 -0.2794)
			(stroke
				(width 0.1)
				(type default)
			)
			(layer "F.Fab")
		)
		(pad "1" smd circle
			(at -0.40005 0 270)
			(size 0 0)
			(layers "F.Cu" "F.Mask" "F.Paste")
			(net "SPI_BIC1_MOSI_LS23_R2")
		)
		(pad "2" smd circle
			(at 0.40005 0 270)
			(size 0 0)
			(layers "F.Cu" "F.Mask" "F.Paste")
			(net "SPI_BIC1_MOSI_LS23_R")
		)
	)
)
